(kicad_pcb
	(version 20260206)
	(generator "pcbnew")
	(generator_version "10.0")
	(general
		(thickness 1.6)
		(legacy_teardrops no)
	)
	(paper "A4")
	(title_block
		(title "01162023_DA0F0TEBIF0_F0T_Expander_BD_F_brd_V02_OCP.brd")
		(comment 1 "Grand Teton / footprints 4149-4154 of 9728")
	)
	(layers
		(0 "F.Cu" signal "TOP")
		(4 "In1.Cu" signal "GND")
		(6 "In2.Cu" signal "VCC")
		(8 "In3.Cu" signal "VCC1")
		(10 "In4.Cu" signal "GND1")
		(12 "In5.Cu" signal "IN1")
		(14 "In6.Cu" signal "GND2")
		(16 "In7.Cu" signal "IN2")
		(18 "In8.Cu" signal "GND3")
		(20 "In9.Cu" signal "IN3")
		(22 "In10.Cu" signal "GND4")
		(24 "In11.Cu" signal "IN4")
		(26 "In12.Cu" signal "GND5")
		(28 "In13.Cu" signal "IN5")
		(30 "In14.Cu" signal "GND6")
		(32 "In15.Cu" signal "IN6")
		(34 "In16.Cu" signal "GND7")
		(2 "B.Cu" signal "BOTTOM")
		(9 "F.Adhes" user "F.Adhesive")
		(11 "B.Adhes" user "B.Adhesive")
		(13 "F.Paste" user "Package Geometry/Pastemask Top")
		(15 "B.Paste" user "Package Geometry/Pastemask Bottom")
		(5 "F.SilkS" user "Ref Des/Silkscreen Top")
		(7 "B.SilkS" user "Ref Des/Silkscreen Bottom")
		(1 "F.Mask" user "Board Geometry/Soldermask Top")
		(3 "B.Mask" user "Board Geometry/Soldermask Bottom")
		(17 "Dwgs.User" user "User.Drawings")
		(19 "Cmts.User" user "User.Comments")
		(21 "Eco1.User" user "User.Eco1")
		(23 "Eco2.User" user "User.Eco2")
		(25 "Edge.Cuts" user "Board Geometry/Outline")
		(27 "Margin" user)
		(31 "F.CrtYd" user "Package Geometry/Place Bound Top")
		(29 "B.CrtYd" user "Package Geometry/Place Bound Bottom")
		(35 "F.Fab" user "Ref Des/Assembly Top")
		(33 "B.Fab" user "Ref Des/Assembly Bottom")
	)
	(footprint ""
		(layer "F.Cu")
		(at 240.121948 -83.951318)
		(property "Reference" "R6723"
			(at 0 0 0)
			(layer "F.SilkS")
			(hide yes)
			(effects
				(font
					(size 1.27 1.27)
				)
			)
		)
		(property "Value" ""
			(at 0 0 0)
			(layer "F.Fab")
			(effects
				(font
					(size 1.27 1.27)
				)
			)
		)
		(duplicate_pad_numbers_are_jumpers no)
		(fp_line
			(start -0.7874 -0.4064)
			(end 0.7874 -0.4064)
			(stroke
				(width 0.1524)
				(type default)
			)
			(layer "F.SilkS")
		)
		(fp_line
			(start -0.7874 0.4064)
			(end -0.7874 -0.4064)
			(stroke
				(width 0.1524)
				(type default)
			)
			(layer "F.SilkS")
		)
		(fp_line
			(start 0.7874 -0.4064)
			(end 0.7874 0.4064)
			(stroke
				(width 0.1524)
				(type default)
			)
			(layer "F.SilkS")
		)
		(fp_line
			(start 0.7874 0.4064)
			(end 0.007366 0.4064)
			(stroke
				(width 0.1524)
				(type default)
			)
			(layer "F.SilkS")
		)
		(fp_line
			(start -0.67945 -0.305054)
			(end -0.12065 -0.305054)
			(stroke
				(width 0.1)
				(type default)
			)
			(layer "F.Fab")
		)
		(fp_line
			(start -0.67945 0.3048)
			(end -0.67945 -0.305054)
			(stroke
				(width 0.1)
				(type default)
			)
			(layer "F.Fab")
		)
		(fp_line
			(start -0.12065 -0.305054)
			(end -0.12065 -0.2794)
			(stroke
				(width 0.1)
				(type default)
			)
			(layer "F.Fab")
		)
		(fp_line
			(start -0.12065 -0.2794)
			(end 0.12065 -0.2794)
			(stroke
				(width 0.1)
				(type default)
			)
			(layer "F.Fab")
		)
		(fp_line
			(start -0.12065 0.2794)
			(end -0.12065 0.3048)
			(stroke
				(width 0.1)
				(type default)
			)
			(layer "F.Fab")
		)
		(fp_line
			(start -0.12065 0.3048)
			(end -0.67945 0.3048)
			(stroke
				(width 0.1)
				(type default)
			)
			(layer "F.Fab")
		)
		(fp_line
			(start 0.120396 0.2794)
			(end -0.12065 0.2794)
			(stroke
				(width 0.1)
				(type default)
			)
			(layer "F.Fab")
		)
		(fp_line
			(start 0.120396 0.3048)
			(end 0.120396 0.2794)
			(stroke
				(width 0.1)
				(type default)
			)
			(layer "F.Fab")
		)
		(fp_line
			(start 0.12065 -0.3048)
			(end 0.67945 -0.3048)
			(stroke
				(width 0.1)
				(type default)
			)
			(layer "F.Fab")
		)
		(fp_line
			(start 0.12065 -0.2794)
			(end 0.12065 -0.3048)
			(stroke
				(width 0.1)
				(type default)
			)
			(layer "F.Fab")
		)
		(fp_line
			(start 0.67945 -0.3048)
			(end 0.67945 0.3048)
			(stroke
				(width 0.1)
				(type default)
			)
			(layer "F.Fab")
		)
		(fp_line
			(start 0.67945 0.3048)
			(end 0.120396 0.3048)
			(stroke
				(width 0.1)
				(type default)
			)
			(layer "F.Fab")
		)
		(pad "1" smd rect
			(at -0.40005 0 180)
			(size 0.4572 0.508)
			(layers "F.Cu" "F.Mask" "F.Paste")
			(net "USB2_CP2108_CLI_DP")
		)
		(pad "2" smd rect
			(at 0.40005 0 180)
			(size 0.4572 0.508)
			(layers "F.Cu" "F.Mask" "F.Paste")
			(net "GND")
		)
	)
	(footprint ""
		(layer "F.Cu")
		(at 149.211538 -258.234434)
		(property "Reference" "L109"
			(at 0 0 0)
			(layer "F.SilkS")
			(hide yes)
			(effects
				(font
					(size 1.27 1.27)
				)
			)
		)
		(property "Value" ""
			(at 0 0 0)
			(layer "F.Fab")
			(effects
				(font
					(size 1.27 1.27)
				)
			)
		)
		(duplicate_pad_numbers_are_jumpers no)
		(fp_line
			(start -1.63576 -0.8128)
			(end -1.63576 0.8128)
			(stroke
				(width 0.1524)
				(type default)
			)
			(layer "F.SilkS")
		)
		(fp_line
			(start -1.63576 -0.8128)
			(end 1.63576 -0.8128)
			(stroke
				(width 0.1524)
				(type default)
			)
			(layer "F.SilkS")
		)
		(fp_line
			(start 1.63576 -0.8128)
			(end 1.63576 0.8128)
			(stroke
				(width 0.1524)
				(type default)
			)
			(layer "F.SilkS")
		)
		(fp_line
			(start 1.63576 0.8128)
			(end -1.63576 0.8128)
			(stroke
				(width 0.1524)
				(type default)
			)
			(layer "F.SilkS")
		)
		(fp_line
			(start -1.56083 -0.738632)
			(end -1.56083 0.7366)
			(stroke
				(width 0.1)
				(type default)
			)
			(layer "F.Fab")
		)
		(fp_line
			(start -1.56083 0.7366)
			(end -1.524 0.7366)
			(stroke
				(width 0.1)
				(type default)
			)
			(layer "F.Fab")
		)
		(fp_line
			(start -1.524 0.7366)
			(end 1.524 0.7366)
			(stroke
				(width 0.1)
				(type default)
			)
			(layer "F.Fab")
		)
		(fp_line
			(start 1.524 0.7366)
			(end 1.560576 0.7366)
			(stroke
				(width 0.1)
				(type default)
			)
			(layer "F.Fab")
		)
		(fp_line
			(start 1.560576 -0.738632)
			(end -1.56083 -0.738632)
			(stroke
				(width 0.1)
				(type default)
			)
			(layer "F.Fab")
		)
		(fp_line
			(start 1.560576 0.7366)
			(end 1.560576 -0.738632)
			(stroke
				(width 0.1)
				(type default)
			)
			(layer "F.Fab")
		)
		(pad "1" smd rect
			(at -0.94996 0 180)
			(size 1.1176 1.3716)
			(layers "F.Cu" "F.Mask" "F.Paste")
			(net "P1V8_PLL0_PEX1")
		)
		(pad "2" smd rect
			(at 0.94996 0 180)
			(size 1.1176 1.3716)
			(layers "F.Cu" "F.Mask" "F.Paste")
			(net "PCEPLL5_VDDA18_PEX1")
		)
	)
	(footprint ""
		(layer "F.Cu")
		(at 365.506 -199.771 180)
		(property "Reference" "R4687"
			(at 0 0 180)
			(layer "F.SilkS")
			(hide yes)
			(effects
				(font
					(size 1.27 1.27)
				)
			)
		)
		(property "Value" ""
			(at 0 0 180)
			(layer "F.Fab")
			(effects
				(font
					(size 1.27 1.27)
				)
			)
		)
		(duplicate_pad_numbers_are_jumpers no)
		(fp_line
			(start 0.7874 0.4064)
			(end -0.7874 0.4064)
			(stroke
				(width 0.1524)
				(type default)
			)
			(layer "F.SilkS")
		)
		(fp_line
			(start 0.7874 -0.4064)
			(end 0.7874 0.4064)
			(stroke
				(width 0.1524)
				(type default)
			)
			(layer "F.SilkS")
		)
		(fp_line
			(start -0.7874 0.4064)
			(end -0.7874 -0.4064)
			(stroke
				(width 0.1524)
				(type default)
			)
			(layer "F.SilkS")
		)
		(fp_line
			(start -0.7874 -0.4064)
			(end 0.7874 -0.4064)
			(stroke
				(width 0.1524)
				(type default)
			)
			(layer "F.SilkS")
		)
		(fp_line
			(start 0.67945 0.3048)
			(end 0.120396 0.3048)
			(stroke
				(width 0.1)
				(type default)
			)
			(layer "F.Fab")
		)
		(fp_line
			(start 0.67945 -0.3048)
			(end 0.67945 0.3048)
			(stroke
				(width 0.1)
				(type default)
			)
			(layer "F.Fab")
		)
		(fp_line
			(start 0.12065 -0.2794)
			(end 0.12065 -0.3048)
			(stroke
				(width 0.1)
				(type default)
			)
			(layer "F.Fab")
		)
		(fp_line
			(start 0.12065 -0.3048)
			(end 0.67945 -0.3048)
			(stroke
				(width 0.1)
				(type default)
			)
			(layer "F.Fab")
		)
		(fp_line
			(start 0.120396 0.3048)
			(end 0.120396 0.2794)
			(stroke
				(width 0.1)
				(type default)
			)
			(layer "F.Fab")
		)
		(fp_line
			(start 0.120396 0.2794)
			(end -0.12065 0.2794)
			(stroke
				(width 0.1)
				(type default)
			)
			(layer "F.Fab")
		)
		(fp_line
			(start -0.12065 0.3048)
			(end -0.67945 0.3048)
			(stroke
				(width 0.1)
				(type default)
			)
			(layer "F.Fab")
		)
		(fp_line
			(start -0.12065 0.2794)
			(end -0.12065 0.3048)
			(stroke
				(width 0.1)
				(type default)
			)
			(layer "F.Fab")
		)
		(fp_line
			(start -0.12065 -0.2794)
			(end 0.12065 -0.2794)
			(stroke
				(width 0.1)
				(type default)
			)
			(layer "F.Fab")
		)
		(fp_line
			(start -0.12065 -0.305054)
			(end -0.12065 -0.2794)
			(stroke
				(width 0.1)
				(type default)
			)
			(layer "F.Fab")
		)
		(fp_line
			(start -0.67945 0.3048)
			(end -0.67945 -0.305054)
			(stroke
				(width 0.1)
				(type default)
			)
			(layer "F.Fab")
		)
		(fp_line
			(start -0.67945 -0.305054)
			(end -0.12065 -0.305054)
			(stroke
				(width 0.1)
				(type default)
			)
			(layer "F.Fab")
		)
		(pad "1" smd circle
			(at -0.40005 0 180)
			(size 0 0)
			(layers "F.Cu" "F.Mask" "F.Paste")
			(net "SSD4_PEX_PWR_EN")
		)
		(pad "2" smd circle
			(at 0.40005 0 180)
			(size 0 0)
			(layers "F.Cu" "F.Mask" "F.Paste")
			(net "SSD4_PEX_PWR_EN_R")
		)
	)
	(footprint ""
		(layer "F.Cu")
		(at 38.566344 -250.070874 -90)
		(property "Reference" "R1127"
			(at 0 0 270)
			(layer "F.SilkS")
			(hide yes)
			(effects
				(font
					(size 1.27 1.27)
				)
			)
		)
		(property "Value" ""
			(at 0 0 270)
			(layer "F.Fab")
			(effects
				(font
					(size 1.27 1.27)
				)
			)
		)
		(duplicate_pad_numbers_are_jumpers no)
		(fp_line
			(start -0.7874 0.4064)
			(end -0.7874 -0.4064)
			(stroke
				(width 0.1524)
				(type default)
			)
			(layer "F.SilkS")
		)
		(fp_line
			(start 0.7874 0.4064)
			(end -0.7874 0.4064)
			(stroke
				(width 0.1524)
				(type default)
			)
			(layer "F.SilkS")
		)
		(fp_line
			(start -0.7874 -0.4064)
			(end 0.7874 -0.4064)
			(stroke
				(width 0.1524)
				(type default)
			)
			(layer "F.SilkS")
		)
		(fp_line
			(start 0.7874 -0.4064)
			(end 0.7874 0.4064)
			(stroke
				(width 0.1524)
				(type default)
			)
			(layer "F.SilkS")
		)
		(fp_line
			(start -0.67945 0.3048)
			(end -0.67945 -0.305054)
			(stroke
				(width 0.1)
				(type default)
			)
			(layer "F.Fab")
		)
		(fp_line
			(start -0.12065 0.3048)
			(end -0.67945 0.3048)
			(stroke
				(width 0.1)
				(type default)
			)
			(layer "F.Fab")
		)
		(fp_line
			(start 0.120396 0.3048)
			(end 0.120396 0.2794)
			(stroke
				(width 0.1)
				(type default)
			)
			(layer "F.Fab")
		)
		(fp_line
			(start 0.67945 0.3048)
			(end 0.120396 0.3048)
			(stroke
				(width 0.1)
				(type default)
			)
			(layer "F.Fab")
		)
		(fp_line
			(start -0.12065 0.2794)
			(end -0.12065 0.3048)
			(stroke
				(width 0.1)
				(type default)
			)
			(layer "F.Fab")
		)
		(fp_line
			(start 0.120396 0.2794)
			(end -0.12065 0.2794)
			(stroke
				(width 0.1)
				(type default)
			)
			(layer "F.Fab")
		)
		(fp_line
			(start -0.12065 -0.2794)
			(end 0.12065 -0.2794)
			(stroke
				(width 0.1)
				(type default)
			)
			(layer "F.Fab")
		)
		(fp_line
			(start 0.12065 -0.2794)
			(end 0.12065 -0.3048)
			(stroke
				(width 0.1)
				(type default)
			)
			(layer "F.Fab")
		)
		(fp_line
			(start 0.12065 -0.3048)
			(end 0.67945 -0.3048)
			(stroke
				(width 0.1)
				(type default)
			)
			(layer "F.Fab")
		)
		(fp_line
			(start 0.67945 -0.3048)
			(end 0.67945 0.3048)
			(stroke
				(width 0.1)
				(type default)
			)
			(layer "F.Fab")
		)
		(fp_line
			(start -0.67945 -0.305054)
			(end -0.12065 -0.305054)
			(stroke
				(width 0.1)
				(type default)
			)
			(layer "F.Fab")
		)
		(fp_line
			(start -0.12065 -0.305054)
			(end -0.12065 -0.2794)
			(stroke
				(width 0.1)
				(type default)
			)
			(layer "F.Fab")
		)
		(pad "1" smd circle
			(at -0.40005 0 270)
			(size 0 0)
			(layers "F.Cu" "F.Mask" "F.Paste")
			(net "PEX0_DBG_MODE4")
		)
		(pad "2" smd circle
			(at 0.40005 0 270)
			(size 0 0)
			(layers "F.Cu" "F.Mask" "F.Paste")
			(net "P1V8_PEX")
		)
	)
	(footprint ""
		(layer "F.Cu")
		(at 136.773158 -22.867366 90)
		(property "Reference" "C3900"
			(at 0 0 90)
			(layer "F.SilkS")
			(hide yes)
			(effects
				(font
					(size 1.27 1.27)
				)
			)
		)
		(property "Value" ""
			(at 0 0 90)
			(layer "F.Fab")
			(effects
				(font
					(size 1.27 1.27)
				)
			)
		)
		(duplicate_pad_numbers_are_jumpers no)
		(fp_line
			(start 0.7874 -0.4064)
			(end 0.7874 0.4064)
			(stroke
				(width 0.1524)
				(type default)
			)
			(layer "F.SilkS")
		)
		(fp_line
			(start -0.7874 -0.4064)
			(end 0.7874 -0.4064)
			(stroke
				(width 0.1524)
				(type default)
			)
			(layer "F.SilkS")
		)
		(fp_line
			(start 0.7874 0.4064)
			(end -0.7874 0.4064)
			(stroke
				(width 0.1524)
				(type default)
			)
			(layer "F.SilkS")
		)
		(fp_line
			(start -0.7874 0.4064)
			(end -0.7874 -0.4064)
			(stroke
				(width 0.1524)
				(type default)
			)
			(layer "F.SilkS")
		)
		(fp_line
			(start -0.12065 -0.305054)
			(end -0.12065 -0.2794)
			(stroke
				(width 0.1)
				(type default)
			)
			(layer "F.Fab")
		)
		(fp_line
			(start -0.67945 -0.305054)
			(end -0.12065 -0.305054)
			(stroke
				(width 0.1)
				(type default)
			)
			(layer "F.Fab")
		)
		(fp_line
			(start 0.67945 -0.3048)
			(end 0.67945 0.3048)
			(stroke
				(width 0.1)
				(type default)
			)
			(layer "F.Fab")
		)
		(fp_line
			(start 0.12065 -0.3048)
			(end 0.67945 -0.3048)
			(stroke
				(width 0.1)
				(type default)
			)
			(layer "F.Fab")
		)
		(fp_line
			(start 0.12065 -0.2794)
			(end 0.12065 -0.3048)
			(stroke
				(width 0.1)
				(type default)
			)
			(layer "F.Fab")
		)
		(fp_line
			(start -0.12065 -0.2794)
			(end 0.12065 -0.2794)
			(stroke
				(width 0.1)
				(type default)
			)
			(layer "F.Fab")
		)
		(fp_line
			(start 0.120396 0.2794)
			(end -0.12065 0.2794)
			(stroke
				(width 0.1)
				(type default)
			)
			(layer "F.Fab")
		)
		(fp_line
			(start -0.12065 0.2794)
			(end -0.12065 0.3048)
			(stroke
				(width 0.1)
				(type default)
			)
			(layer "F.Fab")
		)
		(fp_line
			(start 0.67945 0.3048)
			(end 0.120396 0.3048)
			(stroke
				(width 0.1)
				(type default)
			)
			(layer "F.Fab")
		)
		(fp_line
			(start 0.120396 0.3048)
			(end 0.120396 0.2794)
			(stroke
				(width 0.1)
				(type default)
			)
			(layer "F.Fab")
		)
		(fp_line
			(start -0.12065 0.3048)
			(end -0.67945 0.3048)
			(stroke
				(width 0.1)
				(type default)
			)
			(layer "F.Fab")
		)
		(fp_line
			(start -0.67945 0.3048)
			(end -0.67945 -0.305054)
			(stroke
				(width 0.1)
				(type default)
			)
			(layer "F.Fab")
		)
		(pad "1" smd circle
			(at -0.40005 0 90)
			(size 0 0)
			(layers "F.Cu" "F.Mask" "F.Paste")
			(net "P12V_SSD4")
		)
		(pad "2" smd circle
			(at 0.40005 0 90)
			(size 0 0)
			(layers "F.Cu" "F.Mask" "F.Paste")
			(net "GND")
		)
	)
	(footprint ""
		(layer "F.Cu")
		(at 148.073364 -382.453896)
		(property "Reference" "R6770"
			(at 0 0 0)
			(layer "F.SilkS")
			(hide yes)
			(effects
				(font
					(size 1.27 1.27)
				)
			)
		)
		(property "Value" ""
			(at 0 0 0)
			(layer "F.Fab")
			(effects
				(font
					(size 1.27 1.27)
				)
			)
		)
		(duplicate_pad_numbers_are_jumpers no)
		(fp_line
			(start -0.7874 -0.4064)
			(end 0.7874 -0.4064)
			(stroke
				(width 0.1524)
				(type default)
			)
			(layer "F.SilkS")
		)
		(fp_line
			(start -0.7874 0.4064)
			(end -0.7874 -0.4064)
			(stroke
				(width 0.1524)
				(type default)
			)
			(layer "F.SilkS")
		)
		(fp_line
			(start 0.7874 -0.4064)
			(end 0.7874 0.4064)
			(stroke
				(width 0.1524)
				(type default)
			)
			(layer "F.SilkS")
		)
		(fp_line
			(start 0.7874 0.4064)
			(end -0.7874 0.4064)
			(stroke
				(width 0.1524)
				(type default)
			)
			(layer "F.SilkS")
		)
		(fp_line
			(start -0.67945 -0.305054)
			(end -0.12065 -0.305054)
			(stroke
				(width 0.1)
				(type default)
			)
			(layer "F.Fab")
		)
		(fp_line
			(start -0.67945 0.3048)
			(end -0.67945 -0.305054)
			(stroke
				(width 0.1)
				(type default)
			)
			(layer "F.Fab")
		)
		(fp_line
			(start -0.12065 -0.305054)
			(end -0.12065 -0.2794)
			(stroke
				(width 0.1)
				(type default)
			)
			(layer "F.Fab")
		)
		(fp_line
			(start -0.12065 -0.2794)
			(end 0.12065 -0.2794)
			(stroke
				(width 0.1)
				(type default)
			)
			(layer "F.Fab")
		)
		(fp_line
			(start -0.12065 0.2794)
			(end -0.12065 0.3048)
			(stroke
				(width 0.1)
				(type default)
			)
			(layer "F.Fab")
		)
		(fp_line
			(start -0.12065 0.3048)
			(end -0.67945 0.3048)
			(stroke
				(width 0.1)
				(type default)
			)
			(layer "F.Fab")
		)
		(fp_line
			(start 0.120396 0.2794)
			(end -0.12065 0.2794)
			(stroke
				(width 0.1)
				(type default)
			)
			(layer "F.Fab")
		)
		(fp_line
			(start 0.120396 0.3048)
			(end 0.120396 0.2794)
			(stroke
				(width 0.1)
				(type default)
			)
			(layer "F.Fab")
		)
		(fp_line
			(start 0.12065 -0.3048)
			(end 0.67945 -0.3048)
			(stroke
				(width 0.1)
				(type default)
			)
			(layer "F.Fab")
		)
		(fp_line
			(start 0.12065 -0.2794)
			(end 0.12065 -0.3048)
			(stroke
				(width 0.1)
				(type default)
			)
			(layer "F.Fab")
		)
		(fp_line
			(start 0.67945 -0.3048)
			(end 0.67945 0.3048)
			(stroke
				(width 0.1)
				(type default)
			)
			(layer "F.Fab")
		)
		(fp_line
			(start 0.67945 0.3048)
			(end 0.120396 0.3048)
			(stroke
				(width 0.1)
				(type default)
			)
			(layer "F.Fab")
		)
		(pad "1" smd circle
			(at -0.40005 0)
			(size 0 0)
			(layers "F.Cu" "F.Mask" "F.Paste")
			(net "PRSNT_SWB_B3_N")
		)
		(pad "2" smd circle
			(at 0.40005 0)
			(size 0 0)
			(layers "F.Cu" "F.Mask" "F.Paste")
			(net "GND")
		)
	)
)
